(kicad_pcb
	(version 20260206)
	(generator "pcbnew")
	(generator_version "10.0")
	(general
		(thickness 1.6)
		(legacy_teardrops no)
	)
	(paper "A4")
	(title_block
		(title "01162023_DA0F0TEBIF0_F0T_Expander_BD_F_brd_V02_OCP.brd")
		(comment 1 "Grand Teton / footprints 3924-3930 of 9728")
	)
	(layers
		(0 "F.Cu" signal "TOP")
		(4 "In1.Cu" signal "GND")
		(6 "In2.Cu" signal "VCC")
		(8 "In3.Cu" signal "VCC1")
		(10 "In4.Cu" signal "GND1")
		(12 "In5.Cu" signal "IN1")
		(14 "In6.Cu" signal "GND2")
		(16 "In7.Cu" signal "IN2")
		(18 "In8.Cu" signal "GND3")
		(20 "In9.Cu" signal "IN3")
		(22 "In10.Cu" signal "GND4")
		(24 "In11.Cu" signal "IN4")
		(26 "In12.Cu" signal "GND5")
		(28 "In13.Cu" signal "IN5")
		(30 "In14.Cu" signal "GND6")
		(32 "In15.Cu" signal "IN6")
		(34 "In16.Cu" signal "GND7")
		(2 "B.Cu" signal "BOTTOM")
		(9 "F.Adhes" user "F.Adhesive")
		(11 "B.Adhes" user "B.Adhesive")
		(13 "F.Paste" user "Package Geometry/Pastemask Top")
		(15 "B.Paste" user "Package Geometry/Pastemask Bottom")
		(5 "F.SilkS" user "Ref Des/Silkscreen Top")
		(7 "B.SilkS" user "Ref Des/Silkscreen Bottom")
		(1 "F.Mask" user "Board Geometry/Soldermask Top")
		(3 "B.Mask" user "Board Geometry/Soldermask Bottom")
		(17 "Dwgs.User" user "User.Drawings")
		(19 "Cmts.User" user "User.Comments")
		(21 "Eco1.User" user "User.Eco1")
		(23 "Eco2.User" user "User.Eco2")
		(25 "Edge.Cuts" user "Board Geometry/Outline")
		(27 "Margin" user)
		(31 "F.CrtYd" user "Package Geometry/Place Bound Top")
		(29 "B.CrtYd" user "Package Geometry/Place Bound Bottom")
		(35 "F.Fab" user "Ref Des/Assembly Top")
		(33 "B.Fab" user "Ref Des/Assembly Bottom")
	)
	(footprint ""
		(layer "F.Cu")
		(at 221.297246 -277.128224 90)
		(property "Reference" "R781"
			(at 0 0 90)
			(layer "F.SilkS")
			(hide yes)
			(effects
				(font
					(size 1.27 1.27)
				)
			)
		)
		(property "Value" ""
			(at 0 0 90)
			(layer "F.Fab")
			(effects
				(font
					(size 1.27 1.27)
				)
			)
		)
		(duplicate_pad_numbers_are_jumpers no)
		(fp_line
			(start 3.937508 -1.8796)
			(end -3.937508 -1.8796)
			(stroke
				(width 0.1524)
				(type default)
			)
			(layer "F.SilkS")
		)
		(fp_line
			(start -3.937508 -1.8796)
			(end -3.937508 1.8796)
			(stroke
				(width 0.1524)
				(type default)
			)
			(layer "F.SilkS")
		)
		(fp_line
			(start 3.937508 1.8796)
			(end 3.937508 -1.8796)
			(stroke
				(width 0.1524)
				(type default)
			)
			(layer "F.SilkS")
		)
		(fp_line
			(start -3.937508 1.8796)
			(end 3.937508 1.8796)
			(stroke
				(width 0.1524)
				(type default)
			)
			(layer "F.SilkS")
		)
		(fp_line
			(start 3.275076 -1.674876)
			(end -3.275076 -1.674876)
			(stroke
				(width 0.1)
				(type default)
			)
			(layer "F.Fab")
		)
		(fp_line
			(start -3.275076 -1.674876)
			(end -3.275076 1.674876)
			(stroke
				(width 0.1)
				(type default)
			)
			(layer "F.Fab")
		)
		(fp_line
			(start 3.275076 1.674876)
			(end 3.275076 -1.674876)
			(stroke
				(width 0.1)
				(type default)
			)
			(layer "F.Fab")
		)
		(fp_line
			(start -3.275076 1.674876)
			(end 3.275076 1.674876)
			(stroke
				(width 0.1)
				(type default)
			)
			(layer "F.Fab")
		)
		(pad "1" smd rect
			(at -2.350008 0 90)
			(size 2.921 3.5052)
			(layers "F.Cu" "F.Mask" "F.Paste")
			(net "P1V25_PEX1")
		)
		(pad "2" smd rect
			(at 2.350008 0 90)
			(size 2.921 3.5052)
			(layers "F.Cu" "F.Mask" "F.Paste")
			(net "P1V25_PEX1_R")
		)
	)
	(footprint ""
		(layer "F.Cu")
		(at 2.231644 -21.317712 -90)
		(property "Reference" "R5731"
			(at 0 0 270)
			(layer "F.SilkS")
			(hide yes)
			(effects
				(font
					(size 1.27 1.27)
				)
			)
		)
		(property "Value" ""
			(at 0 0 270)
			(layer "F.Fab")
			(effects
				(font
					(size 1.27 1.27)
				)
			)
		)
		(duplicate_pad_numbers_are_jumpers no)
		(fp_line
			(start -0.7874 0.4064)
			(end -0.7874 -0.4064)
			(stroke
				(width 0.1524)
				(type default)
			)
			(layer "F.SilkS")
		)
		(fp_line
			(start 0.7874 0.4064)
			(end -0.7874 0.4064)
			(stroke
				(width 0.1524)
				(type default)
			)
			(layer "F.SilkS")
		)
		(fp_line
			(start -0.7874 -0.4064)
			(end 0.7874 -0.4064)
			(stroke
				(width 0.1524)
				(type default)
			)
			(layer "F.SilkS")
		)
		(fp_line
			(start 0.7874 -0.4064)
			(end 0.7874 0.4064)
			(stroke
				(width 0.1524)
				(type default)
			)
			(layer "F.SilkS")
		)
		(fp_line
			(start -0.67945 0.3048)
			(end -0.67945 -0.305054)
			(stroke
				(width 0.1)
				(type default)
			)
			(layer "F.Fab")
		)
		(fp_line
			(start -0.12065 0.3048)
			(end -0.67945 0.3048)
			(stroke
				(width 0.1)
				(type default)
			)
			(layer "F.Fab")
		)
		(fp_line
			(start 0.120396 0.3048)
			(end 0.120396 0.2794)
			(stroke
				(width 0.1)
				(type default)
			)
			(layer "F.Fab")
		)
		(fp_line
			(start 0.67945 0.3048)
			(end 0.120396 0.3048)
			(stroke
				(width 0.1)
				(type default)
			)
			(layer "F.Fab")
		)
		(fp_line
			(start -0.12065 0.2794)
			(end -0.12065 0.3048)
			(stroke
				(width 0.1)
				(type default)
			)
			(layer "F.Fab")
		)
		(fp_line
			(start 0.120396 0.2794)
			(end -0.12065 0.2794)
			(stroke
				(width 0.1)
				(type default)
			)
			(layer "F.Fab")
		)
		(fp_line
			(start -0.12065 -0.2794)
			(end 0.12065 -0.2794)
			(stroke
				(width 0.1)
				(type default)
			)
			(layer "F.Fab")
		)
		(fp_line
			(start 0.12065 -0.2794)
			(end 0.12065 -0.3048)
			(stroke
				(width 0.1)
				(type default)
			)
			(layer "F.Fab")
		)
		(fp_line
			(start 0.12065 -0.3048)
			(end 0.67945 -0.3048)
			(stroke
				(width 0.1)
				(type default)
			)
			(layer "F.Fab")
		)
		(fp_line
			(start 0.67945 -0.3048)
			(end 0.67945 0.3048)
			(stroke
				(width 0.1)
				(type default)
			)
			(layer "F.Fab")
		)
		(fp_line
			(start -0.67945 -0.305054)
			(end -0.12065 -0.305054)
			(stroke
				(width 0.1)
				(type default)
			)
			(layer "F.Fab")
		)
		(fp_line
			(start -0.12065 -0.305054)
			(end -0.12065 -0.2794)
			(stroke
				(width 0.1)
				(type default)
			)
			(layer "F.Fab")
		)
		(pad "1" smd circle
			(at -0.40005 0 270)
			(size 0 0)
			(layers "F.Cu" "F.Mask" "F.Paste")
			(net "P3V3_SSD0")
		)
		(pad "2" smd circle
			(at 0.40005 0 270)
			(size 0 0)
			(layers "F.Cu" "F.Mask" "F.Paste")
			(net "SSD0_LED_ISO_N")
		)
	)
	(footprint ""
		(layer "F.Cu")
		(at 278.451056 -399.00098 90)
		(property "Reference" "U146"
			(at 0.051562 2.121154 90)
			(unlocked yes)
			(layer "F.SilkS")
			(effects
				(font
					(size 0.7874 0.5842)
					(thickness 0.1524)
				)
			)
		)
		(property "Value" ""
			(at 0 0 90)
			(layer "F.Fab")
			(effects
				(font
					(size 1.27 1.27)
				)
			)
		)
		(duplicate_pad_numbers_are_jumpers no)
		(fp_line
			(start 1.7272 -1.1176)
			(end 0.254 -1.1176)
			(stroke
				(width 0.1524)
				(type default)
			)
			(layer "F.SilkS")
		)
		(fp_line
			(start 1.7272 -1.1176)
			(end 1.7272 1.1176)
			(stroke
				(width 0.1524)
				(type default)
			)
			(layer "F.SilkS")
		)
		(fp_line
			(start 0.254 -1.1176)
			(end 0 -0.7366)
			(stroke
				(width 0.1524)
				(type default)
			)
			(layer "F.SilkS")
		)
		(fp_line
			(start -0.254 -1.1176)
			(end -1.7272 -1.1176)
			(stroke
				(width 0.1524)
				(type default)
			)
			(layer "F.SilkS")
		)
		(fp_line
			(start 0 -0.7366)
			(end -0.254 -1.1176)
			(stroke
				(width 0.1524)
				(type default)
			)
			(layer "F.SilkS")
		)
		(fp_line
			(start 1.7272 1.1176)
			(end -1.7272 1.1176)
			(stroke
				(width 0.1524)
				(type default)
			)
			(layer "F.SilkS")
		)
		(fp_line
			(start -1.7272 1.1176)
			(end -1.7272 -1.1176)
			(stroke
				(width 0.1524)
				(type default)
			)
			(layer "F.SilkS")
		)
		(fp_poly
			(pts
				(xy -1.9558 -0.649986) (xy -2.7178 -0.268986) (xy -2.7178 -1.030986)
			)
			(stroke
				(width 0)
				(type default)
			)
			(fill yes)
			(layer "F.SilkS")
		)
		(fp_line
			(start 1.5748 -1.1176)
			(end -1.5748 -1.1176)
			(stroke
				(width 0.1)
				(type default)
			)
			(layer "F.Fab")
		)
		(fp_line
			(start -1.5748 -1.1176)
			(end -1.5748 1.1176)
			(stroke
				(width 0.1)
				(type default)
			)
			(layer "F.Fab")
		)
		(fp_line
			(start 1.5748 1.1176)
			(end 1.5748 -1.1176)
			(stroke
				(width 0.1)
				(type default)
			)
			(layer "F.Fab")
		)
		(fp_line
			(start -1.5748 1.1176)
			(end 1.5748 1.1176)
			(stroke
				(width 0.1)
				(type default)
			)
			(layer "F.Fab")
		)
		(fp_poly
			(pts
				(xy -1.9558 -0.649986) (xy -2.7178 -0.268986) (xy -2.7178 -1.030986)
			)
			(stroke
				(width 0)
				(type default)
			)
			(fill yes)
			(layer "F.Fab")
		)
		(pad "1" smd rect
			(at -0.999998 -0.649986)
			(size 0.3556 1.1176)
			(layers "F.Cu" "F.Mask" "F.Paste")
			(net "MB_BMC_MON")
		)
		(pad "2" smd rect
			(at -0.999998 0)
			(size 0.3556 1.1176)
			(layers "F.Cu" "F.Mask" "F.Paste")
			(net "GND")
		)
		(pad "3" smd rect
			(at -0.999998 0.649986)
			(size 0.3556 1.1176)
			(layers "F.Cu" "F.Mask" "F.Paste")
			(net "RST_MB_BIC_N")
		)
		(pad "4" smd rect
			(at 0.999998 0.649986)
			(size 0.3556 1.1176)
			(layers "F.Cu" "F.Mask" "F.Paste")
			(net "RST_MB_BIC_ISO_N")
		)
		(pad "5" smd rect
			(at 0.999998 0)
			(size 0.3556 1.1176)
			(layers "F.Cu" "F.Mask" "F.Paste")
			(net "P3V3_AUX")
		)
		(pad "6" smd rect
			(at 0.999998 -0.649986)
			(size 0.3556 1.1176)
			(layers "F.Cu" "F.Mask" "F.Paste")
			(net "MB_BMC_MON_ISO")
		)
	)
	(footprint ""
		(layer "F.Cu")
		(at 476.630238 -525.953736)
		(property "Reference" "J19_12"
			(at -0.5842 -1.31953 0)
			(unlocked yes)
			(layer "B.SilkS")
			(effects
				(font
					(size 0.7874 0.5842)
					(thickness 0.1524)
				)
				(justify left mirror)
			)
		)
		(property "Value" ""
			(at 0 0 0)
			(layer "F.Fab")
			(effects
				(font
					(size 1.27 1.27)
				)
			)
		)
		(duplicate_pad_numbers_are_jumpers no)
		(pad "1" thru_hole circle
			(at 0 0)
			(size 0.4572 0.4572)
			(drill 0.2032)
			(layers "*.Cu" "*.Mask")
			(remove_unused_layers no)
			(net "Net_468")
			(clearance 0.127)
			(thermal_gap 0.127)
			(padstack
				(mode front_inner_back)
				(layer "Inner"
					(shape circle)
					(size 0.4572 0.4572)
					(clearance 0.127)
				)
				(layer "B.Cu"
					(shape circle)
					(size 0.508 0.508)
					(clearance 0.1016)
				)
			)
		)
	)
	(footprint ""
		(layer "F.Cu")
		(at 37.248084 -101.095302)
		(property "Reference" "C61"
			(at 0 0 0)
			(layer "F.SilkS")
			(hide yes)
			(effects
				(font
					(size 1.27 1.27)
				)
			)
		)
		(property "Value" ""
			(at 0 0 0)
			(layer "F.Fab")
			(effects
				(font
					(size 1.27 1.27)
				)
			)
		)
		(duplicate_pad_numbers_are_jumpers no)
		(fp_line
			(start -0.299974 -0.150114)
			(end 0.299974 -0.150114)
			(stroke
				(width 0.1)
				(type default)
			)
			(layer "F.Fab")
		)
		(fp_line
			(start -0.299974 0.150114)
			(end -0.299974 -0.150114)
			(stroke
				(width 0.1)
				(type default)
			)
			(layer "F.Fab")
		)
		(fp_line
			(start 0.299974 -0.150114)
			(end 0.299974 0.150114)
			(stroke
				(width 0.1)
				(type default)
			)
			(layer "F.Fab")
		)
		(fp_line
			(start 0.299974 0.150114)
			(end -0.299974 0.150114)
			(stroke
				(width 0.1)
				(type default)
			)
			(layer "F.Fab")
		)
		(pad "1" smd rect
			(at -0.2667 0)
			(size 0.3048 0.381)
			(layers "F.Cu" "F.Mask" "F.Paste")
			(net "P5E_PEX0_STN1_TX_DN<17>")
		)
		(pad "2" smd rect
			(at 0.2667 0)
			(size 0.3048 0.381)
			(layers "F.Cu" "F.Mask" "F.Paste")
			(net "P5E_PEX0_STN1_TX_C_DN<17>")
		)
	)
	(footprint ""
		(layer "F.Cu")
		(at 151.228044 -441.600082)
		(property "Reference" "X15"
			(at -0.1778 -1.92913 0)
			(unlocked yes)
			(layer "F.SilkS")
			(effects
				(font
					(size 0.7874 0.5842)
					(thickness 0.1524)
				)
				(justify left)
			)
		)
		(property "Value" ""
			(at 0 0 0)
			(layer "F.Fab")
			(effects
				(font
					(size 1.27 1.27)
				)
			)
		)
		(property "Device Type" "TP_TDR_4P_FTS_MPKT4_H025P0200_IO_TP15_TP_TDR_4P_DIP"
			(at 1.30175 1.27 90)
			(unlocked yes)
			(layer "F.Fab")
			(hide yes)
			(effects
				(font
					(size 0.635 0.4064)
					(thickness 0.1524)
				)
			)
		)
		(property "User Part Number" "TP15"
			(at 1.30175 1.27 90)
			(unlocked yes)
			(layer "Cmts.User")
			(hide yes)
			(effects
				(font
					(size 0.635 0.4064)
					(thickness 0.1524)
				)
			)
		)
		(duplicate_pad_numbers_are_jumpers no)
		(fp_line
			(start 0 -1.27)
			(end 0 -0.635)
			(stroke
				(width 0.1524)
				(type default)
			)
			(layer "F.SilkS")
		)
		(fp_line
			(start 0 0.635)
			(end 0 1.905)
			(stroke
				(width 0.1524)
				(type default)
			)
			(layer "F.SilkS")
		)
		(fp_line
			(start 0 3.175)
			(end 0 3.81)
			(stroke
				(width 0.1524)
				(type default)
			)
			(layer "F.SilkS")
		)
		(fp_line
			(start 0 3.81)
			(end 2.54 3.81)
			(stroke
				(width 0.1524)
				(type default)
			)
			(layer "F.SilkS")
		)
		(fp_line
			(start 2.54 -1.27)
			(end 0 -1.27)
			(stroke
				(width 0.1524)
				(type default)
			)
			(layer "F.SilkS")
		)
		(fp_line
			(start 2.54 -1.1303)
			(end 2.54 -1.27)
			(stroke
				(width 0.1524)
				(type default)
			)
			(layer "F.SilkS")
		)
		(fp_line
			(start 2.54 1.4097)
			(end 2.54 1.1303)
			(stroke
				(width 0.1524)
				(type default)
			)
			(layer "F.SilkS")
		)
		(fp_line
			(start 2.54 3.81)
			(end 2.54 3.6703)
			(stroke
				(width 0.1524)
				(type default)
			)
			(layer "F.SilkS")
		)
		(fp_poly
			(pts
				(xy -0.761746 0) (xy -2.285746 -0.762) (xy -2.285746 0.762)
			)
			(stroke
				(width 0)
				(type default)
			)
			(fill yes)
			(layer "F.SilkS")
		)
		(fp_line
			(start 0 -1.27)
			(end 0 3.81)
			(stroke
				(width 0.1)
				(type default)
			)
			(layer "F.Fab")
		)
		(fp_line
			(start 0 3.81)
			(end 2.54 3.81)
			(stroke
				(width 0.1)
				(type default)
			)
			(layer "F.Fab")
		)
		(fp_line
			(start 2.54 -1.27)
			(end 0 -1.27)
			(stroke
				(width 0.1)
				(type default)
			)
			(layer "F.Fab")
		)
		(fp_line
			(start 2.54 3.81)
			(end 2.54 -1.27)
			(stroke
				(width 0.1)
				(type default)
			)
			(layer "F.Fab")
		)
		(fp_poly
			(pts
				(xy -0.761746 0) (xy -2.285746 -0.762) (xy -2.285746 0.762)
			)
			(stroke
				(width 0)
				(type default)
			)
			(fill yes)
			(layer "F.Fab")
		)
		(pad "1" thru_hole circle
			(at 0 0)
			(size 1.0033 1.0033)
			(drill 0.249936)
			(layers "*.Cu" "*.Mask")
			(remove_unused_layers no)
			(net "TDR_DIFF_85_IN2_DIN")
			(clearance 0.10795)
			(thermal_gap 0.10795)
			(padstack
				(mode front_inner_back)
				(layer "Inner"
					(shape circle)
					(size 0.8001 0.8001)
					(clearance 0.1524)
				)
				(layer "B.Cu"
					(shape circle)
					(size 1.0033 1.0033)
					(clearance 0.10795)
				)
			)
		)
		(pad "2" thru_hole circle
			(at 2.54 0)
			(size 1.9939 1.9939)
			(drill 0.249936)
			(layers "*.Cu" "*.Mask")
			(remove_unused_layers no)
			(net "COUPON_GND1")
			(clearance 0.10795)
			(thermal_gap 0.10795)
			(padstack
				(mode front_inner_back)
				(layer "Inner"
					(shape circle)
					(size 0.8001 0.8001)
					(clearance 0.1524)
				)
				(layer "B.Cu"
					(shape circle)
					(size 1.9939 1.9939)
					(clearance 0.10795)
				)
			)
		)
		(pad "3" thru_hole circle
			(at 2.54 2.54)
			(size 1.9939 1.9939)
			(drill 0.249936)
			(layers "*.Cu" "*.Mask")
			(remove_unused_layers no)
			(net "COUPON_GND1")
			(clearance 0.10795)
			(thermal_gap 0.10795)
			(padstack
				(mode front_inner_back)
				(layer "Inner"
					(shape circle)
					(size 0.8001 0.8001)
					(clearance 0.1524)
				)
				(layer "B.Cu"
					(shape circle)
					(size 1.9939 1.9939)
					(clearance 0.10795)
				)
			)
		)
		(pad "4" thru_hole circle
			(at 0 2.54)
			(size 1.0033 1.0033)
			(drill 0.249936)
			(layers "*.Cu" "*.Mask")
			(remove_unused_layers no)
			(net "TDR_DIFF_85_IN2_DIP")
			(clearance 0.10795)
			(thermal_gap 0.10795)
			(padstack
				(mode front_inner_back)
				(layer "Inner"
					(shape circle)
					(size 0.8001 0.8001)
					(clearance 0.1524)
				)
				(layer "B.Cu"
					(shape circle)
					(size 1.0033 1.0033)
					(clearance 0.10795)
				)
			)
		)
	)
	(footprint ""
		(layer "F.Cu")
		(at 309.262272 -22.955504 -90)
		(property "Reference" "C2729"
			(at 0 0 270)
			(layer "F.SilkS")
			(hide yes)
			(effects
				(font
					(size 1.27 1.27)
				)
			)
		)
		(property "Value" ""
			(at 0 0 270)
			(layer "F.Fab")
			(effects
				(font
					(size 1.27 1.27)
				)
			)
		)
		(duplicate_pad_numbers_are_jumpers no)
		(fp_line
			(start -0.7874 0.4064)
			(end -0.7874 -0.4064)
			(stroke
				(width 0.1524)
				(type default)
			)
			(layer "F.SilkS")
		)
		(fp_line
			(start 0.7874 0.4064)
			(end -0.7874 0.4064)
			(stroke
				(width 0.1524)
				(type default)
			)
			(layer "F.SilkS")
		)
		(fp_line
			(start -0.7874 -0.4064)
			(end 0.7874 -0.4064)
			(stroke
				(width 0.1524)
				(type default)
			)
			(layer "F.SilkS")
		)
		(fp_line
			(start 0.7874 -0.4064)
			(end 0.7874 0.4064)
			(stroke
				(width 0.1524)
				(type default)
			)
			(layer "F.SilkS")
		)
		(fp_line
			(start -0.67945 0.3048)
			(end -0.67945 -0.305054)
			(stroke
				(width 0.1)
				(type default)
			)
			(layer "F.Fab")
		)
		(fp_line
			(start -0.12065 0.3048)
			(end -0.67945 0.3048)
			(stroke
				(width 0.1)
				(type default)
			)
			(layer "F.Fab")
		)
		(fp_line
			(start 0.120396 0.3048)
			(end 0.120396 0.2794)
			(stroke
				(width 0.1)
				(type default)
			)
			(layer "F.Fab")
		)
		(fp_line
			(start 0.67945 0.3048)
			(end 0.120396 0.3048)
			(stroke
				(width 0.1)
				(type default)
			)
			(layer "F.Fab")
		)
		(fp_line
			(start -0.12065 0.2794)
			(end -0.12065 0.3048)
			(stroke
				(width 0.1)
				(type default)
			)
			(layer "F.Fab")
		)
		(fp_line
			(start 0.120396 0.2794)
			(end -0.12065 0.2794)
			(stroke
				(width 0.1)
				(type default)
			)
			(layer "F.Fab")
		)
		(fp_line
			(start -0.12065 -0.2794)
			(end 0.12065 -0.2794)
			(stroke
				(width 0.1)
				(type default)
			)
			(layer "F.Fab")
		)
		(fp_line
			(start 0.12065 -0.2794)
			(end 0.12065 -0.3048)
			(stroke
				(width 0.1)
				(type default)
			)
			(layer "F.Fab")
		)
		(fp_line
			(start 0.12065 -0.3048)
			(end 0.67945 -0.3048)
			(stroke
				(width 0.1)
				(type default)
			)
			(layer "F.Fab")
		)
		(fp_line
			(start 0.67945 -0.3048)
			(end 0.67945 0.3048)
			(stroke
				(width 0.1)
				(type default)
			)
			(layer "F.Fab")
		)
		(fp_line
			(start -0.67945 -0.305054)
			(end -0.12065 -0.305054)
			(stroke
				(width 0.1)
				(type default)
			)
			(layer "F.Fab")
		)
		(fp_line
			(start -0.12065 -0.305054)
			(end -0.12065 -0.2794)
			(stroke
				(width 0.1)
				(type default)
			)
			(layer "F.Fab")
		)
		(pad "1" smd circle
			(at -0.40005 0 270)
			(size 0 0)
			(layers "F.Cu" "F.Mask" "F.Paste")
			(net "GND")
		)
		(pad "2" smd circle
			(at 0.40005 0 270)
			(size 0 0)
			(layers "F.Cu" "F.Mask" "F.Paste")
			(net "P3V3_AUX")
		)
	)
)
